# S9S_MB_2U (Grand Teton) — schematic netlist excerpt (pin names and nets, part order shuffled) for the footprints in the layout excerpt that follows; sources: Cadence DE-HDL packaged netlist, KiCad conversion of 03242023_DA0F0TMBIJ0_F0T_Motherboard_J_brd_V01_OCP.brd

R3093  Q_RES  130 1% CHIP  pkg 0402LF  page 254 : A = LED_PWRGD_PVCCD_HV_CPU1 ; B = P3V3_AUX
R3574  Q_RES  10 1% CHIP  pkg 0402LF  page 172 : A = P3V3 ; B = VSENSE_P12V_INA230_4_INP

(kicad_pcb
	(version 20260206)
	(generator "pcbnew")
	(generator_version "10.0")
	(general
		(thickness 1.6)
		(legacy_teardrops no)
	)
	(paper "A4")
	(title_block
		(title "03242023_DA0F0TMBIJ0_F0T_Motherboard_J_brd_V01_OCP.brd")
		(comment 1 "Grand Teton / footprints 865-866 of 6105")
	)
	(layers
		(0 "F.Cu" signal "TOP")
		(4 "In1.Cu" signal "GND")
		(6 "In2.Cu" signal "IN1")
		(8 "In3.Cu" signal "GND1")
		(10 "In4.Cu" signal "IN2")
		(12 "In5.Cu" signal "GND2")
		(14 "In6.Cu" signal "IN3")
		(16 "In7.Cu" signal "GND3")
		(18 "In8.Cu" signal "VCC")
		(20 "In9.Cu" signal "VCC1")
		(22 "In10.Cu" signal "GND4")
		(24 "In11.Cu" signal "IN4")
		(26 "In12.Cu" signal "GND5")
		(28 "In13.Cu" signal "IN5")
		(30 "In14.Cu" signal "GND6")
		(32 "In15.Cu" signal "IN6")
		(34 "In16.Cu" signal "GND7")
		(2 "B.Cu" signal "BOTTOM")
		(9 "F.Adhes" user "F.Adhesive")
		(11 "B.Adhes" user "B.Adhesive")
		(13 "F.Paste" user "Package Geometry/Pastemask Top")
		(15 "B.Paste" user "Package Geometry/Pastemask Bottom")
		(5 "F.SilkS" user "Ref Des/Silkscreen Top")
		(7 "B.SilkS" user "Ref Des/Silkscreen Bottom")
		(1 "F.Mask" user "Board Geometry/Soldermask Top")
		(3 "B.Mask" user "Board Geometry/Soldermask Bottom")
		(17 "Dwgs.User" user "User.Drawings")
		(19 "Cmts.User" user "User.Comments")
		(21 "Eco1.User" user "User.Eco1")
		(23 "Eco2.User" user "User.Eco2")
		(25 "Edge.Cuts" user "Board Geometry/Outline")
		(27 "Margin" user)
		(31 "F.CrtYd" user "Package Geometry/Place Bound Top")
		(29 "B.CrtYd" user "Package Geometry/Place Bound Bottom")
		(35 "F.Fab" user "Ref Des/Assembly Top")
		(33 "B.Fab" user "Ref Des/Assembly Bottom")
	)
	(footprint ""
		(layer "F.Cu")
		(at 80.381602 -74.901552 -90)
		(property "Reference" "R3093"
			(at 0 0 270)
			(layer "F.SilkS")
			(hide yes)
			(effects
				(font
					(size 1.27 1.27)
				)
			)
		)
		(property "Value" ""
			(at 0 0 270)
			(layer "F.Fab")
			(effects
				(font
					(size 1.27 1.27)
				)
			)
		)
		(duplicate_pad_numbers_are_jumpers no)
		(fp_line
			(start -0.7874 0.4064)
			(end -0.7874 -0.4064)
			(stroke
				(width 0.1524)
				(type default)
			)
			(layer "F.SilkS")
		)
		(fp_line
			(start 0.7874 0.4064)
			(end -0.7874 0.4064)
			(stroke
				(width 0.1524)
				(type default)
			)
			(layer "F.SilkS")
		)
		(fp_line
			(start -0.7874 -0.4064)
			(end 0.7874 -0.4064)
			(stroke
				(width 0.1524)
				(type default)
			)
			(layer "F.SilkS")
		)
		(fp_line
			(start 0.7874 -0.4064)
			(end 0.7874 0.4064)
			(stroke
				(width 0.1524)
				(type default)
			)
			(layer "F.SilkS")
		)
		(fp_line
			(start -0.67945 0.3048)
			(end -0.67945 -0.305054)
			(stroke
				(width 0.1)
				(type default)
			)
			(layer "F.Fab")
		)
		(fp_line
			(start -0.12065 0.3048)
			(end -0.67945 0.3048)
			(stroke
				(width 0.1)
				(type default)
			)
			(layer "F.Fab")
		)
		(fp_line
			(start 0.120396 0.3048)
			(end 0.120396 0.2794)
			(stroke
				(width 0.1)
				(type default)
			)
			(layer "F.Fab")
		)
		(fp_line
			(start 0.67945 0.3048)
			(end 0.120396 0.3048)
			(stroke
				(width 0.1)
				(type default)
			)
			(layer "F.Fab")
		)
		(fp_line
			(start -0.12065 0.2794)
			(end -0.12065 0.3048)
			(stroke
				(width 0.1)
				(type default)
			)
			(layer "F.Fab")
		)
		(fp_line
			(start 0.120396 0.2794)
			(end -0.12065 0.2794)
			(stroke
				(width 0.1)
				(type default)
			)
			(layer "F.Fab")
		)
		(fp_line
			(start -0.12065 -0.2794)
			(end 0.12065 -0.2794)
			(stroke
				(width 0.1)
				(type default)
			)
			(layer "F.Fab")
		)
		(fp_line
			(start 0.12065 -0.2794)
			(end 0.12065 -0.3048)
			(stroke
				(width 0.1)
				(type default)
			)
			(layer "F.Fab")
		)
		(fp_line
			(start 0.12065 -0.3048)
			(end 0.67945 -0.3048)
			(stroke
				(width 0.1)
				(type default)
			)
			(layer "F.Fab")
		)
		(fp_line
			(start 0.67945 -0.3048)
			(end 0.67945 0.3048)
			(stroke
				(width 0.1)
				(type default)
			)
			(layer "F.Fab")
		)
		(fp_line
			(start -0.67945 -0.305054)
			(end -0.12065 -0.305054)
			(stroke
				(width 0.1)
				(type default)
			)
			(layer "F.Fab")
		)
		(fp_line
			(start -0.12065 -0.305054)
			(end -0.12065 -0.2794)
			(stroke
				(width 0.1)
				(type default)
			)
			(layer "F.Fab")
		)
		(pad "1" smd circle
			(at -0.40005 0 270)
			(size 0 0)
			(layers "F.Cu" "F.Mask" "F.Paste")
			(net "LED_PWRGD_PVCCD_HV_CPU1")
		)
		(pad "2" smd circle
			(at 0.40005 0 270)
			(size 0 0)
			(layers "F.Cu" "F.Mask" "F.Paste")
			(net "P3V3_AUX")
		)
	)
	(footprint ""
		(layer "F.Cu")
		(at 159.267144 -53.867304 180)
		(property "Reference" "R3574"
			(at 0 0 180)
			(layer "F.SilkS")
			(hide yes)
			(effects
				(font
					(size 1.27 1.27)
				)
			)
		)
		(property "Value" ""
			(at 0 0 180)
			(layer "F.Fab")
			(effects
				(font
					(size 1.27 1.27)
				)
			)
		)
		(duplicate_pad_numbers_are_jumpers no)
		(fp_line
			(start 0.7874 0.4064)
			(end -0.7874 0.4064)
			(stroke
				(width 0.1524)
				(type default)
			)
			(layer "F.SilkS")
		)
		(fp_line
			(start 0.7874 -0.4064)
			(end 0.7874 0.4064)
			(stroke
				(width 0.1524)
				(type default)
			)
			(layer "F.SilkS")
		)
		(fp_line
			(start -0.7874 0.4064)
			(end -0.7874 -0.4064)
			(stroke
				(width 0.1524)
				(type default)
			)
			(layer "F.SilkS")
		)
		(fp_line
			(start -0.7874 -0.4064)
			(end 0.7874 -0.4064)
			(stroke
				(width 0.1524)
				(type default)
			)
			(layer "F.SilkS")
		)
		(fp_line
			(start 0.67945 0.3048)
			(end 0.120396 0.3048)
			(stroke
				(width 0.1)
				(type default)
			)
			(layer "F.Fab")
		)
		(fp_line
			(start 0.67945 -0.3048)
			(end 0.67945 0.3048)
			(stroke
				(width 0.1)
				(type default)
			)
			(layer "F.Fab")
		)
		(fp_line
			(start 0.12065 -0.2794)
			(end 0.12065 -0.3048)
			(stroke
				(width 0.1)
				(type default)
			)
			(layer "F.Fab")
		)
		(fp_line
			(start 0.12065 -0.3048)
			(end 0.67945 -0.3048)
			(stroke
				(width 0.1)
				(type default)
			)
			(layer "F.Fab")
		)
		(fp_line
			(start 0.120396 0.3048)
			(end 0.120396 0.2794)
			(stroke
				(width 0.1)
				(type default)
			)
			(layer "F.Fab")
		)
		(fp_line
			(start 0.120396 0.2794)
			(end -0.12065 0.2794)
			(stroke
				(width 0.1)
				(type default)
			)
			(layer "F.Fab")
		)
		(fp_line
			(start -0.12065 0.3048)
			(end -0.67945 0.3048)
			(stroke
				(width 0.1)
				(type default)
			)
			(layer "F.Fab")
		)
		(fp_line
			(start -0.12065 0.2794)
			(end -0.12065 0.3048)
			(stroke
				(width 0.1)
				(type default)
			)
			(layer "F.Fab")
		)
		(fp_line
			(start -0.12065 -0.2794)
			(end 0.12065 -0.2794)
			(stroke
				(width 0.1)
				(type default)
			)
			(layer "F.Fab")
		)
		(fp_line
			(start -0.12065 -0.305054)
			(end -0.12065 -0.2794)
			(stroke
				(width 0.1)
				(type default)
			)
			(layer "F.Fab")
		)
		(fp_line
			(start -0.67945 0.3048)
			(end -0.67945 -0.305054)
			(stroke
				(width 0.1)
				(type default)
			)
			(layer "F.Fab")
		)
		(fp_line
			(start -0.67945 -0.305054)
			(end -0.12065 -0.305054)
			(stroke
				(width 0.1)
				(type default)
			)
			(layer "F.Fab")
		)
		(pad "1" smd circle
			(at -0.40005 0 180)
			(size 0 0)
			(layers "F.Cu" "F.Mask" "F.Paste")
			(net "P3V3")
		)
		(pad "2" smd circle
			(at 0.40005 0 180)
			(size 0 0)
			(layers "F.Cu" "F.Mask" "F.Paste")
			(net "VSENSE_P12V_INA230_4_INP")
		)
	)
)
